(kicad_pcb
	(version 20260206)
	(generator "pcbnew")
	(generator_version "10.0")
	(general
		(thickness 1.6)
		(legacy_teardrops no)
	)
	(paper "A4")
	(title_block
		(title "03242023_DA0F0TMBIJ0_F0T_Motherboard_J_brd_V01_OCP.brd")
		(comment 1 "Grand Teton / footprints 6077-6084 of 6105")
	)
	(layers
		(0 "F.Cu" signal "TOP")
		(4 "In1.Cu" signal "GND")
		(6 "In2.Cu" signal "IN1")
		(8 "In3.Cu" signal "GND1")
		(10 "In4.Cu" signal "IN2")
		(12 "In5.Cu" signal "GND2")
		(14 "In6.Cu" signal "IN3")
		(16 "In7.Cu" signal "GND3")
		(18 "In8.Cu" signal "VCC")
		(20 "In9.Cu" signal "VCC1")
		(22 "In10.Cu" signal "GND4")
		(24 "In11.Cu" signal "IN4")
		(26 "In12.Cu" signal "GND5")
		(28 "In13.Cu" signal "IN5")
		(30 "In14.Cu" signal "GND6")
		(32 "In15.Cu" signal "IN6")
		(34 "In16.Cu" signal "GND7")
		(2 "B.Cu" signal "BOTTOM")
		(9 "F.Adhes" user "F.Adhesive")
		(11 "B.Adhes" user "B.Adhesive")
		(13 "F.Paste" user "Package Geometry/Pastemask Top")
		(15 "B.Paste" user "Package Geometry/Pastemask Bottom")
		(5 "F.SilkS" user "Ref Des/Silkscreen Top")
		(7 "B.SilkS" user "Ref Des/Silkscreen Bottom")
		(1 "F.Mask" user "Board Geometry/Soldermask Top")
		(3 "B.Mask" user "Board Geometry/Soldermask Bottom")
		(17 "Dwgs.User" user "User.Drawings")
		(19 "Cmts.User" user "User.Comments")
		(21 "Eco1.User" user "User.Eco1")
		(23 "Eco2.User" user "User.Eco2")
		(25 "Edge.Cuts" user "Board Geometry/Outline")
		(27 "Margin" user)
		(31 "F.CrtYd" user "Package Geometry/Place Bound Top")
		(29 "B.CrtYd" user "Package Geometry/Place Bound Bottom")
		(35 "F.Fab" user "Ref Des/Assembly Top")
		(33 "B.Fab" user "Ref Des/Assembly Bottom")
	)
	(footprint ""
		(layer "B.Cu")
		(at 216.00541 -403.668738 -90)
		(property "Reference" "PR3980"
			(at 0 0 90)
			(layer "B.SilkS")
			(hide yes)
			(effects
				(font
					(size 1.27 1.27)
				)
				(justify mirror)
			)
		)
		(property "Value" ""
			(at 0 0 90)
			(layer "B.Fab")
			(effects
				(font
					(size 1.27 1.27)
				)
				(justify mirror)
			)
		)
		(duplicate_pad_numbers_are_jumpers no)
		(fp_line
			(start -0.7874 0.4064)
			(end 0.7874 0.4064)
			(stroke
				(width 0.1524)
				(type default)
			)
			(layer "B.SilkS")
		)
		(fp_line
			(start 0.7874 0.4064)
			(end 0.7874 -0.4064)
			(stroke
				(width 0.1524)
				(type default)
			)
			(layer "B.SilkS")
		)
		(fp_line
			(start -0.7874 -0.4064)
			(end -0.7874 0.4064)
			(stroke
				(width 0.1524)
				(type default)
			)
			(layer "B.SilkS")
		)
		(fp_line
			(start 0.7874 -0.4064)
			(end -0.7874 -0.4064)
			(stroke
				(width 0.1524)
				(type default)
			)
			(layer "B.SilkS")
		)
		(fp_line
			(start -0.67945 0.3048)
			(end -0.120396 0.3048)
			(stroke
				(width 0.1)
				(type default)
			)
			(layer "B.Fab")
		)
		(fp_line
			(start -0.120396 0.3048)
			(end -0.120396 0.2794)
			(stroke
				(width 0.1)
				(type default)
			)
			(layer "B.Fab")
		)
		(fp_line
			(start 0.12065 0.3048)
			(end 0.67945 0.3048)
			(stroke
				(width 0.1)
				(type default)
			)
			(layer "B.Fab")
		)
		(fp_line
			(start 0.67945 0.3048)
			(end 0.67945 -0.305054)
			(stroke
				(width 0.1)
				(type default)
			)
			(layer "B.Fab")
		)
		(fp_line
			(start -0.120396 0.2794)
			(end 0.12065 0.2794)
			(stroke
				(width 0.1)
				(type default)
			)
			(layer "B.Fab")
		)
		(fp_line
			(start 0.12065 0.2794)
			(end 0.12065 0.3048)
			(stroke
				(width 0.1)
				(type default)
			)
			(layer "B.Fab")
		)
		(fp_line
			(start -0.12065 -0.2794)
			(end -0.12065 -0.3048)
			(stroke
				(width 0.1)
				(type default)
			)
			(layer "B.Fab")
		)
		(fp_line
			(start 0.12065 -0.2794)
			(end -0.12065 -0.2794)
			(stroke
				(width 0.1)
				(type default)
			)
			(layer "B.Fab")
		)
		(fp_line
			(start -0.67945 -0.3048)
			(end -0.67945 0.3048)
			(stroke
				(width 0.1)
				(type default)
			)
			(layer "B.Fab")
		)
		(fp_line
			(start -0.12065 -0.3048)
			(end -0.67945 -0.3048)
			(stroke
				(width 0.1)
				(type default)
			)
			(layer "B.Fab")
		)
		(fp_line
			(start 0.12065 -0.305054)
			(end 0.12065 -0.2794)
			(stroke
				(width 0.1)
				(type default)
			)
			(layer "B.Fab")
		)
		(fp_line
			(start 0.67945 -0.305054)
			(end 0.12065 -0.305054)
			(stroke
				(width 0.1)
				(type default)
			)
			(layer "B.Fab")
		)
		(pad "1" smd circle
			(at 0.40005 0 90)
			(size 0 0)
			(layers "B.Cu" "B.Mask" "B.Paste")
			(net "HSC_VDD_R_3")
		)
		(pad "2" smd circle
			(at -0.40005 0 90)
			(size 0 0)
			(layers "B.Cu" "B.Mask" "B.Paste")
			(net "HSC_VDD")
		)
	)
	(footprint ""
		(layer "B.Cu")
		(at 315.11748 -56.276748 180)
		(property "Reference" "R1486"
			(at 0 0 0)
			(layer "B.SilkS")
			(hide yes)
			(effects
				(font
					(size 1.27 1.27)
				)
				(justify mirror)
			)
		)
		(property "Value" ""
			(at 0 0 0)
			(layer "B.Fab")
			(effects
				(font
					(size 1.27 1.27)
				)
				(justify mirror)
			)
		)
		(duplicate_pad_numbers_are_jumpers no)
		(fp_line
			(start 0.7874 0.4064)
			(end 0.7874 -0.4064)
			(stroke
				(width 0.1524)
				(type default)
			)
			(layer "B.SilkS")
		)
		(fp_line
			(start 0.7874 -0.4064)
			(end -0.7874 -0.4064)
			(stroke
				(width 0.1524)
				(type default)
			)
			(layer "B.SilkS")
		)
		(fp_line
			(start -0.7874 0.4064)
			(end 0.7874 0.4064)
			(stroke
				(width 0.1524)
				(type default)
			)
			(layer "B.SilkS")
		)
		(fp_line
			(start -0.7874 -0.4064)
			(end -0.7874 0.4064)
			(stroke
				(width 0.1524)
				(type default)
			)
			(layer "B.SilkS")
		)
		(fp_line
			(start 0.67945 0.3048)
			(end 0.67945 -0.305054)
			(stroke
				(width 0.1)
				(type default)
			)
			(layer "B.Fab")
		)
		(fp_line
			(start 0.67945 -0.305054)
			(end 0.12065 -0.305054)
			(stroke
				(width 0.1)
				(type default)
			)
			(layer "B.Fab")
		)
		(fp_line
			(start 0.12065 0.3048)
			(end 0.67945 0.3048)
			(stroke
				(width 0.1)
				(type default)
			)
			(layer "B.Fab")
		)
		(fp_line
			(start 0.12065 0.2794)
			(end 0.12065 0.3048)
			(stroke
				(width 0.1)
				(type default)
			)
			(layer "B.Fab")
		)
		(fp_line
			(start 0.12065 -0.2794)
			(end -0.12065 -0.2794)
			(stroke
				(width 0.1)
				(type default)
			)
			(layer "B.Fab")
		)
		(fp_line
			(start 0.12065 -0.305054)
			(end 0.12065 -0.2794)
			(stroke
				(width 0.1)
				(type default)
			)
			(layer "B.Fab")
		)
		(fp_line
			(start -0.120396 0.3048)
			(end -0.120396 0.2794)
			(stroke
				(width 0.1)
				(type default)
			)
			(layer "B.Fab")
		)
		(fp_line
			(start -0.120396 0.2794)
			(end 0.12065 0.2794)
			(stroke
				(width 0.1)
				(type default)
			)
			(layer "B.Fab")
		)
		(fp_line
			(start -0.12065 -0.2794)
			(end -0.12065 -0.3048)
			(stroke
				(width 0.1)
				(type default)
			)
			(layer "B.Fab")
		)
		(fp_line
			(start -0.12065 -0.3048)
			(end -0.67945 -0.3048)
			(stroke
				(width 0.1)
				(type default)
			)
			(layer "B.Fab")
		)
		(fp_line
			(start -0.67945 0.3048)
			(end -0.120396 0.3048)
			(stroke
				(width 0.1)
				(type default)
			)
			(layer "B.Fab")
		)
		(fp_line
			(start -0.67945 -0.3048)
			(end -0.67945 0.3048)
			(stroke
				(width 0.1)
				(type default)
			)
			(layer "B.Fab")
		)
		(pad "1" smd circle
			(at 0.40005 0)
			(size 0 0)
			(layers "B.Cu" "B.Mask" "B.Paste")
			(net "PVNN_TERM_CPU0")
		)
		(pad "2" smd circle
			(at -0.40005 0)
			(size 0 0)
			(layers "B.Cu" "B.Mask" "B.Paste")
			(net "FM_PCH_TRIGGER1_R_N")
		)
	)
	(footprint ""
		(layer "B.Cu")
		(at 235.9406 -301.023528)
		(property "Reference" ""
			(at 0 0 0)
			(layer "B.SilkS")
			(hide yes)
			(effects
				(font
					(size 1.27 1.27)
				)
				(justify mirror)
			)
		)
		(property "Value" ""
			(at 0 0 0)
			(layer "B.Fab")
			(effects
				(font
					(size 1.27 1.27)
				)
				(justify mirror)
			)
		)
		(duplicate_pad_numbers_are_jumpers no)
		(pad "1" smd circle
			(at 0 0 180)
			(size 0.9906 0.9906)
			(layers "B.Cu" "B.Mask" "B.Paste")
			(net "Net_293")
		)
		(zone
			(layer "B.Cu")
			(hatch none 0.5)
			(connect_pads
				(clearance 0)
			)
			(min_thickness 0.25)
			(keepout
				(tracks not_allowed)
				(vias allowed)
				(pads allowed)
				(copperpour not_allowed)
				(footprints allowed)
			)
			(placement
				(enabled no)
				(sheetname "")
			)
			(fill
				(thermal_gap 0.5)
				(thermal_bridge_width 0.5)
				(island_removal_mode 0)
			)
			(polygon
				(pts
					(arc
						(start 237.5662 -301.023528)
						(mid 234.315 -301.023528)
						(end 237.5662 -301.023528)
					)
				)
			)
		)
	)
	(footprint ""
		(layer "B.Cu")
		(at 160.935162 -41.832784 90)
		(property "Reference" "R4450"
			(at 0 0 90)
			(layer "B.SilkS")
			(hide yes)
			(effects
				(font
					(size 1.27 1.27)
				)
				(justify mirror)
			)
		)
		(property "Value" ""
			(at 0 0 90)
			(layer "B.Fab")
			(effects
				(font
					(size 1.27 1.27)
				)
				(justify mirror)
			)
		)
		(duplicate_pad_numbers_are_jumpers no)
		(fp_line
			(start 0.7874 -0.4064)
			(end -0.7874 -0.4064)
			(stroke
				(width 0.1524)
				(type default)
			)
			(layer "B.SilkS")
		)
		(fp_line
			(start -0.7874 -0.4064)
			(end -0.7874 0.4064)
			(stroke
				(width 0.1524)
				(type default)
			)
			(layer "B.SilkS")
		)
		(fp_line
			(start 0.7874 0.4064)
			(end 0.7874 -0.4064)
			(stroke
				(width 0.1524)
				(type default)
			)
			(layer "B.SilkS")
		)
		(fp_line
			(start -0.7874 0.4064)
			(end 0.7874 0.4064)
			(stroke
				(width 0.1524)
				(type default)
			)
			(layer "B.SilkS")
		)
		(fp_line
			(start 0.67945 -0.305054)
			(end 0.12065 -0.305054)
			(stroke
				(width 0.1)
				(type default)
			)
			(layer "B.Fab")
		)
		(fp_line
			(start 0.12065 -0.305054)
			(end 0.12065 -0.2794)
			(stroke
				(width 0.1)
				(type default)
			)
			(layer "B.Fab")
		)
		(fp_line
			(start -0.12065 -0.3048)
			(end -0.67945 -0.3048)
			(stroke
				(width 0.1)
				(type default)
			)
			(layer "B.Fab")
		)
		(fp_line
			(start -0.67945 -0.3048)
			(end -0.67945 0.3048)
			(stroke
				(width 0.1)
				(type default)
			)
			(layer "B.Fab")
		)
		(fp_line
			(start 0.12065 -0.2794)
			(end -0.12065 -0.2794)
			(stroke
				(width 0.1)
				(type default)
			)
			(layer "B.Fab")
		)
		(fp_line
			(start -0.12065 -0.2794)
			(end -0.12065 -0.3048)
			(stroke
				(width 0.1)
				(type default)
			)
			(layer "B.Fab")
		)
		(fp_line
			(start 0.12065 0.2794)
			(end 0.12065 0.3048)
			(stroke
				(width 0.1)
				(type default)
			)
			(layer "B.Fab")
		)
		(fp_line
			(start -0.120396 0.2794)
			(end 0.12065 0.2794)
			(stroke
				(width 0.1)
				(type default)
			)
			(layer "B.Fab")
		)
		(fp_line
			(start 0.67945 0.3048)
			(end 0.67945 -0.305054)
			(stroke
				(width 0.1)
				(type default)
			)
			(layer "B.Fab")
		)
		(fp_line
			(start 0.12065 0.3048)
			(end 0.67945 0.3048)
			(stroke
				(width 0.1)
				(type default)
			)
			(layer "B.Fab")
		)
		(fp_line
			(start -0.120396 0.3048)
			(end -0.120396 0.2794)
			(stroke
				(width 0.1)
				(type default)
			)
			(layer "B.Fab")
		)
		(fp_line
			(start -0.67945 0.3048)
			(end -0.120396 0.3048)
			(stroke
				(width 0.1)
				(type default)
			)
			(layer "B.Fab")
		)
		(pad "1" smd circle
			(at 0.40005 0 270)
			(size 0 0)
			(layers "B.Cu" "B.Mask" "B.Paste")
			(net "P3V3_AUX")
		)
		(pad "2" smd circle
			(at -0.40005 0 270)
			(size 0 0)
			(layers "B.Cu" "B.Mask" "B.Paste")
			(net "P3V3_AUX_USB_HUB_2")
		)
	)
	(footprint ""
		(layer "B.Cu")
		(at 234.889294 -132.470906 90)
		(property "Reference" "R575"
			(at 0 0 90)
			(layer "B.SilkS")
			(hide yes)
			(effects
				(font
					(size 1.27 1.27)
				)
				(justify mirror)
			)
		)
		(property "Value" ""
			(at 0 0 90)
			(layer "B.Fab")
			(effects
				(font
					(size 1.27 1.27)
				)
				(justify mirror)
			)
		)
		(duplicate_pad_numbers_are_jumpers no)
		(fp_line
			(start 0.7874 -0.4064)
			(end -0.7874 -0.4064)
			(stroke
				(width 0.1524)
				(type default)
			)
			(layer "B.SilkS")
		)
		(fp_line
			(start -0.7874 -0.4064)
			(end -0.7874 0.4064)
			(stroke
				(width 0.1524)
				(type default)
			)
			(layer "B.SilkS")
		)
		(fp_line
			(start 0.7874 0.4064)
			(end 0.7874 -0.4064)
			(stroke
				(width 0.1524)
				(type default)
			)
			(layer "B.SilkS")
		)
		(fp_line
			(start -0.7874 0.4064)
			(end 0.7874 0.4064)
			(stroke
				(width 0.1524)
				(type default)
			)
			(layer "B.SilkS")
		)
		(fp_line
			(start 0.67945 -0.305054)
			(end 0.12065 -0.305054)
			(stroke
				(width 0.1)
				(type default)
			)
			(layer "B.Fab")
		)
		(fp_line
			(start 0.12065 -0.305054)
			(end 0.12065 -0.2794)
			(stroke
				(width 0.1)
				(type default)
			)
			(layer "B.Fab")
		)
		(fp_line
			(start -0.12065 -0.3048)
			(end -0.67945 -0.3048)
			(stroke
				(width 0.1)
				(type default)
			)
			(layer "B.Fab")
		)
		(fp_line
			(start -0.67945 -0.3048)
			(end -0.67945 0.3048)
			(stroke
				(width 0.1)
				(type default)
			)
			(layer "B.Fab")
		)
		(fp_line
			(start 0.12065 -0.2794)
			(end -0.12065 -0.2794)
			(stroke
				(width 0.1)
				(type default)
			)
			(layer "B.Fab")
		)
		(fp_line
			(start -0.12065 -0.2794)
			(end -0.12065 -0.3048)
			(stroke
				(width 0.1)
				(type default)
			)
			(layer "B.Fab")
		)
		(fp_line
			(start 0.12065 0.2794)
			(end 0.12065 0.3048)
			(stroke
				(width 0.1)
				(type default)
			)
			(layer "B.Fab")
		)
		(fp_line
			(start -0.120396 0.2794)
			(end 0.12065 0.2794)
			(stroke
				(width 0.1)
				(type default)
			)
			(layer "B.Fab")
		)
		(fp_line
			(start 0.67945 0.3048)
			(end 0.67945 -0.305054)
			(stroke
				(width 0.1)
				(type default)
			)
			(layer "B.Fab")
		)
		(fp_line
			(start 0.12065 0.3048)
			(end 0.67945 0.3048)
			(stroke
				(width 0.1)
				(type default)
			)
			(layer "B.Fab")
		)
		(fp_line
			(start -0.120396 0.3048)
			(end -0.120396 0.2794)
			(stroke
				(width 0.1)
				(type default)
			)
			(layer "B.Fab")
		)
		(fp_line
			(start -0.67945 0.3048)
			(end -0.120396 0.3048)
			(stroke
				(width 0.1)
				(type default)
			)
			(layer "B.Fab")
		)
		(pad "1" smd circle
			(at 0.40005 0 270)
			(size 0 0)
			(layers "B.Cu" "B.Mask" "B.Paste")
			(net "FM_PLD_CLKS_DEV_EN")
		)
		(pad "2" smd circle
			(at -0.40005 0 270)
			(size 0 0)
			(layers "B.Cu" "B.Mask" "B.Paste")
			(net "FM_DB2000_DEV_EN")
		)
	)
	(footprint ""
		(layer "B.Cu")
		(at 345.794076 -59.029854 45)
		(property "Reference" "C158"
			(at 0 0 45)
			(layer "B.SilkS")
			(hide yes)
			(effects
				(font
					(size 1.27 1.27)
				)
				(justify mirror)
			)
		)
		(property "Value" ""
			(at 0 0 45)
			(layer "B.Fab")
			(effects
				(font
					(size 1.27 1.27)
				)
				(justify mirror)
			)
		)
		(duplicate_pad_numbers_are_jumpers no)
		(fp_line
			(start -0.299941 -0.15015)
			(end -0.299941 0.15015)
			(stroke
				(width 0.1)
				(type default)
			)
			(layer "B.Fab")
		)
		(fp_line
			(start -0.299941 0.15015)
			(end 0.299941 0.15015)
			(stroke
				(width 0.1)
				(type default)
			)
			(layer "B.Fab")
		)
		(fp_line
			(start 0.299941 -0.15015)
			(end -0.299941 -0.15015)
			(stroke
				(width 0.1)
				(type default)
			)
			(layer "B.Fab")
		)
		(fp_line
			(start 0.299941 0.15015)
			(end 0.299941 -0.15015)
			(stroke
				(width 0.1)
				(type default)
			)
			(layer "B.Fab")
		)
		(pad "1" smd rect
			(at 0.266699 0 225)
			(size 0.3048 0.381)
			(layers "B.Cu" "B.Mask" "B.Paste")
			(net "DMI_CPU0_PCH_RX_C_DP<6>")
		)
		(pad "2" smd rect
			(at -0.266699 0 225)
			(size 0.3048 0.381)
			(layers "B.Cu" "B.Mask" "B.Paste")
			(net "DMI_CPU0_PCH_RX_DP<6>")
		)
	)
	(footprint ""
		(layer "B.Cu")
		(at 181.457346 -321.554856 -90)
		(property "Reference" "C88"
			(at 0 0 90)
			(layer "B.SilkS")
			(hide yes)
			(effects
				(font
					(size 1.27 1.27)
				)
				(justify mirror)
			)
		)
		(property "Value" ""
			(at 0 0 90)
			(layer "B.Fab")
			(effects
				(font
					(size 1.27 1.27)
				)
				(justify mirror)
			)
		)
		(duplicate_pad_numbers_are_jumpers no)
		(fp_line
			(start -1.524 0.762)
			(end 1.524 0.762)
			(stroke
				(width 0.1524)
				(type default)
			)
			(layer "B.SilkS")
		)
		(fp_line
			(start 1.524 0.762)
			(end 1.524 -0.762)
			(stroke
				(width 0.1524)
				(type default)
			)
			(layer "B.SilkS")
		)
		(fp_line
			(start -1.524 -0.762)
			(end -1.524 0.762)
			(stroke
				(width 0.1524)
				(type default)
			)
			(layer "B.SilkS")
		)
		(fp_line
			(start 1.524 -0.762)
			(end -1.524 -0.762)
			(stroke
				(width 0.1524)
				(type default)
			)
			(layer "B.SilkS")
		)
		(fp_line
			(start -1.1049 0.724916)
			(end -1.1049 -0.724916)
			(stroke
				(width 0.1)
				(type default)
			)
			(layer "B.Fab")
		)
		(fp_line
			(start 1.1049 0.724916)
			(end -1.1049 0.724916)
			(stroke
				(width 0.1)
				(type default)
			)
			(layer "B.Fab")
		)
		(fp_line
			(start -1.1049 -0.724916)
			(end 1.1049 -0.724916)
			(stroke
				(width 0.1)
				(type default)
			)
			(layer "B.Fab")
		)
		(fp_line
			(start 1.1049 -0.724916)
			(end 1.1049 0.724916)
			(stroke
				(width 0.1)
				(type default)
			)
			(layer "B.Fab")
		)
		(pad "1" smd rect
			(at 0.889 0 270)
			(size 1.016 1.27)
			(layers "B.Cu" "B.Mask" "B.Paste")
			(net "P12V_S3_AUX_CPU1_NVDIMM")
		)
		(pad "2" smd rect
			(at -0.889 0 270)
			(size 1.016 1.27)
			(layers "B.Cu" "B.Mask" "B.Paste")
			(net "GND")
		)
	)
	(footprint ""
		(layer "B.Cu")
		(at 22.219412 -184.31256 180)
		(property "Reference" "PR3338"
			(at 0 0 0)
			(layer "B.SilkS")
			(hide yes)
			(effects
				(font
					(size 1.27 1.27)
				)
				(justify mirror)
			)
		)
		(property "Value" ""
			(at 0 0 0)
			(layer "B.Fab")
			(effects
				(font
					(size 1.27 1.27)
				)
				(justify mirror)
			)
		)
		(duplicate_pad_numbers_are_jumpers no)
		(fp_line
			(start 0.7874 0.4064)
			(end 0.7874 -0.4064)
			(stroke
				(width 0.1524)
				(type default)
			)
			(layer "B.SilkS")
		)
		(fp_line
			(start 0.7874 -0.4064)
			(end -0.7874 -0.4064)
			(stroke
				(width 0.1524)
				(type default)
			)
			(layer "B.SilkS")
		)
		(fp_line
			(start -0.7874 0.4064)
			(end 0.7874 0.4064)
			(stroke
				(width 0.1524)
				(type default)
			)
			(layer "B.SilkS")
		)
		(fp_line
			(start -0.7874 -0.4064)
			(end -0.7874 0.4064)
			(stroke
				(width 0.1524)
				(type default)
			)
			(layer "B.SilkS")
		)
		(fp_line
			(start 0.67945 0.3048)
			(end 0.67945 -0.305054)
			(stroke
				(width 0.1)
				(type default)
			)
			(layer "B.Fab")
		)
		(fp_line
			(start 0.67945 -0.305054)
			(end 0.12065 -0.305054)
			(stroke
				(width 0.1)
				(type default)
			)
			(layer "B.Fab")
		)
		(fp_line
			(start 0.12065 0.3048)
			(end 0.67945 0.3048)
			(stroke
				(width 0.1)
				(type default)
			)
			(layer "B.Fab")
		)
		(fp_line
			(start 0.12065 0.2794)
			(end 0.12065 0.3048)
			(stroke
				(width 0.1)
				(type default)
			)
			(layer "B.Fab")
		)
		(fp_line
			(start 0.12065 -0.2794)
			(end -0.12065 -0.2794)
			(stroke
				(width 0.1)
				(type default)
			)
			(layer "B.Fab")
		)
		(fp_line
			(start 0.12065 -0.305054)
			(end 0.12065 -0.2794)
			(stroke
				(width 0.1)
				(type default)
			)
			(layer "B.Fab")
		)
		(fp_line
			(start -0.120396 0.3048)
			(end -0.120396 0.2794)
			(stroke
				(width 0.1)
				(type default)
			)
			(layer "B.Fab")
		)
		(fp_line
			(start -0.120396 0.2794)
			(end 0.12065 0.2794)
			(stroke
				(width 0.1)
				(type default)
			)
			(layer "B.Fab")
		)
		(fp_line
			(start -0.12065 -0.2794)
			(end -0.12065 -0.3048)
			(stroke
				(width 0.1)
				(type default)
			)
			(layer "B.Fab")
		)
		(fp_line
			(start -0.12065 -0.3048)
			(end -0.67945 -0.3048)
			(stroke
				(width 0.1)
				(type default)
			)
			(layer "B.Fab")
		)
		(fp_line
			(start -0.67945 0.3048)
			(end -0.120396 0.3048)
			(stroke
				(width 0.1)
				(type default)
			)
			(layer "B.Fab")
		)
		(fp_line
			(start -0.67945 -0.3048)
			(end -0.67945 0.3048)
			(stroke
				(width 0.1)
				(type default)
			)
			(layer "B.Fab")
		)
		(pad "1" smd circle
			(at 0.40005 0)
			(size 0 0)
			(layers "B.Cu" "B.Mask" "B.Paste")
			(net "P3V3_AUX")
		)
		(pad "2" smd circle
			(at -0.40005 0)
			(size 0 0)
			(layers "B.Cu" "B.Mask" "B.Paste")
			(net "PVNN_MAIN_CPU1_VCC")
		)
	)
)
